(kicad_pcb
	(version 20260206)
	(generator "pcbnew")
	(generator_version "10.0")
	(general
		(thickness 1.6)
		(legacy_teardrops no)
	)
	(paper "A4")
	(title_block
		(title "v1-chassis-manager — T6M_CM_d_v01_1031_1645.brd")
		(comment 1 "Open CloudServer (Microsoft) / footprints 2122-2132 of 2512")
	)
	(layers
		(0 "F.Cu" signal "TOP")
		(4 "In1.Cu" signal "GND1")
		(6 "In2.Cu" signal "IN1")
		(8 "In3.Cu" signal "VCC1")
		(10 "In4.Cu" signal "VCC2")
		(12 "In5.Cu" signal "GND2")
		(14 "In6.Cu" signal "IN2")
		(16 "In7.Cu" signal "IN3")
		(18 "In8.Cu" signal "GND3")
		(2 "B.Cu" signal "BOTTOM")
		(9 "F.Adhes" user "F.Adhesive")
		(11 "B.Adhes" user "B.Adhesive")
		(13 "F.Paste" user "Package Geometry/Pastemask Top")
		(15 "B.Paste" user "Package Geometry/Pastemask Bottom")
		(5 "F.SilkS" user "Ref Des/Silkscreen Top")
		(7 "B.SilkS" user "Ref Des/Silkscreen Bottom")
		(1 "F.Mask" user "Board Geometry/Soldermask Top")
		(3 "B.Mask" user "Board Geometry/Soldermask Bottom")
		(17 "Dwgs.User" user "User.Drawings")
		(19 "Cmts.User" user "User.Comments")
		(21 "Eco1.User" user "User.Eco1")
		(23 "Eco2.User" user "User.Eco2")
		(25 "Edge.Cuts" user "Board Geometry/Outline")
		(27 "Margin" user)
		(31 "F.CrtYd" user "Package Geometry/Place Bound Top")
		(29 "B.CrtYd" user "Package Geometry/Place Bound Bottom")
		(35 "F.Fab" user "Ref Des/Assembly Top")
		(33 "B.Fab" user "Ref Des/Assembly Bottom")
	)
	(footprint ""
		(layer "B.Cu")
		(at 160.406588 -198.841614)
		(property "Reference" "TP10"
			(at 0 0 0)
			(layer "B.SilkS")
			(hide yes)
			(effects
				(font
					(size 1.27 1.27)
				)
				(justify mirror)
			)
		)
		(property "Value" ""
			(at 0 0 0)
			(layer "B.Fab")
			(effects
				(font
					(size 1.27 1.27)
				)
				(justify mirror)
			)
		)
		(duplicate_pad_numbers_are_jumpers no)
		(fp_poly
			(pts
				(arc
					(start 0.381 0)
					(mid -0.381 0)
					(end 0.381 0)
				)
			)
			(stroke
				(width 0)
				(type default)
			)
			(fill no)
			(layer "B.CrtYd")
		)
		(pad "1" smd circle
			(at 0 0 180)
			(size 0.762 0.762)
			(layers "B.Cu" "B.Mask" "B.Paste")
			(net "UART_CTS_RP5_L_N")
		)
	)
	(footprint ""
		(layer "B.Cu")
		(at 62.18047 -134.045198)
		(property "Reference" "C289"
			(at -40.632888 52.982368 0)
			(unlocked yes)
			(layer "B.SilkS")
			(effects
				(font
					(size 0.7874 0.5842)
					(thickness 0.1524)
				)
				(justify left mirror)
			)
		)
		(property "Value" ""
			(at 0 0 0)
			(layer "B.Fab")
			(effects
				(font
					(size 1.27 1.27)
				)
				(justify mirror)
			)
		)
		(duplicate_pad_numbers_are_jumpers no)
		(fp_line
			(start -0.7874 -0.4064)
			(end -0.7874 0.4064)
			(stroke
				(width 0.1524)
				(type default)
			)
			(layer "B.SilkS")
		)
		(fp_line
			(start -0.7874 0.4064)
			(end 0.7874 0.4064)
			(stroke
				(width 0.1524)
				(type default)
			)
			(layer "B.SilkS")
		)
		(fp_line
			(start 0 0.381)
			(end 0 -0.381)
			(stroke
				(width 0.1524)
				(type default)
			)
			(layer "B.SilkS")
		)
		(fp_line
			(start 0.7874 -0.4064)
			(end -0.7874 -0.4064)
			(stroke
				(width 0.1524)
				(type default)
			)
			(layer "B.SilkS")
		)
		(fp_line
			(start 0.7874 0.4064)
			(end 0.7874 -0.4064)
			(stroke
				(width 0.1524)
				(type default)
			)
			(layer "B.SilkS")
		)
		(fp_poly
			(pts
				(xy 0.5334 0.254) (xy 0.635 0.254) (xy 0.635 0.2286) (xy 0.635 -0.254) (xy 0.5334 -0.254) (xy 0.5334 -0.2794)
				(xy -0.5334 -0.2794) (xy -0.5334 -0.254) (xy -0.635 -0.254) (xy -0.635 0.254) (xy -0.5334 0.254)
				(xy -0.5334 0.2794) (xy 0.508 0.2794) (xy 0.5334 0.2794)
			)
			(stroke
				(width 0)
				(type default)
			)
			(fill no)
			(layer "B.CrtYd")
		)
		(pad "1" smd rect
			(at -0.40005 0 180)
			(size 0.4572 0.508)
			(layers "B.Cu" "B.Mask" "B.Paste")
			(net "P1V26_BMC_NODE1")
		)
		(pad "2" smd rect
			(at 0.40005 0 180)
			(size 0.4572 0.508)
			(layers "B.Cu" "B.Mask" "B.Paste")
			(net "GND")
		)
	)
	(footprint ""
		(layer "B.Cu")
		(at 64.24676 -185.205624 90)
		(property "Reference" "R865"
			(at 4.15163 0.125984 270)
			(unlocked yes)
			(layer "B.SilkS")
			(effects
				(font
					(size 0.7874 0.5842)
					(thickness 0.1524)
				)
				(justify left mirror)
			)
		)
		(property "Value" ""
			(at 0 0 90)
			(layer "B.Fab")
			(effects
				(font
					(size 1.27 1.27)
				)
				(justify mirror)
			)
		)
		(duplicate_pad_numbers_are_jumpers no)
		(fp_line
			(start 0.7874 -0.4064)
			(end -0.7874 -0.4064)
			(stroke
				(width 0.1524)
				(type default)
			)
			(layer "B.SilkS")
		)
		(fp_line
			(start -0.7874 -0.4064)
			(end -0.7874 0.4064)
			(stroke
				(width 0.1524)
				(type default)
			)
			(layer "B.SilkS")
		)
		(fp_line
			(start 0.7874 0.4064)
			(end 0.7874 -0.4064)
			(stroke
				(width 0.1524)
				(type default)
			)
			(layer "B.SilkS")
		)
		(fp_line
			(start -0.7874 0.4064)
			(end 0.7874 0.4064)
			(stroke
				(width 0.1524)
				(type default)
			)
			(layer "B.SilkS")
		)
		(fp_poly
			(pts
				(xy 0.508 0.2794) (xy 0.508 0.2286) (xy 0.635 0.2286) (xy 0.635 -0.254) (xy 0.5334 -0.254) (xy 0.5334 -0.2794)
				(xy -0.5334 -0.2794) (xy -0.5334 -0.254) (xy -0.635 -0.254) (xy -0.635 0.254) (xy -0.5334 0.254)
				(xy -0.5334 0.2794)
			)
			(stroke
				(width 0)
				(type default)
			)
			(fill no)
			(layer "B.CrtYd")
		)
		(pad "1" smd rect
			(at -0.40005 0 270)
			(size 0.4572 0.508)
			(layers "B.Cu" "B.Mask" "B.Paste")
			(net "T1_NODE3_EN")
		)
		(pad "2" smd rect
			(at 0.40005 0 270)
			(size 0.4572 0.508)
			(layers "B.Cu" "B.Mask" "B.Paste")
			(net "T1_NODE3_EN_R")
		)
	)
	(footprint ""
		(layer "B.Cu")
		(at 77.098652 -179.990242 -90)
		(property "Reference" "R1166"
			(at 5.402834 3.002788 270)
			(unlocked yes)
			(layer "B.SilkS")
			(effects
				(font
					(size 0.7874 0.5842)
					(thickness 0.1524)
				)
				(justify left mirror)
			)
		)
		(property "Value" ""
			(at 0 0 90)
			(layer "B.Fab")
			(effects
				(font
					(size 1.27 1.27)
				)
				(justify mirror)
			)
		)
		(duplicate_pad_numbers_are_jumpers no)
		(fp_line
			(start -0.7874 0.4064)
			(end 0.7874 0.4064)
			(stroke
				(width 0.1524)
				(type default)
			)
			(layer "B.SilkS")
		)
		(fp_line
			(start 0.7874 0.4064)
			(end 0.7874 -0.4064)
			(stroke
				(width 0.1524)
				(type default)
			)
			(layer "B.SilkS")
		)
		(fp_line
			(start -0.7874 -0.4064)
			(end -0.7874 0.4064)
			(stroke
				(width 0.1524)
				(type default)
			)
			(layer "B.SilkS")
		)
		(fp_line
			(start 0.7874 -0.4064)
			(end -0.7874 -0.4064)
			(stroke
				(width 0.1524)
				(type default)
			)
			(layer "B.SilkS")
		)
		(fp_poly
			(pts
				(xy 0.508 0.2794) (xy 0.508 0.2286) (xy 0.635 0.2286) (xy 0.635 -0.254) (xy 0.5334 -0.254) (xy 0.5334 -0.2794)
				(xy -0.5334 -0.2794) (xy -0.5334 -0.254) (xy -0.635 -0.254) (xy -0.635 0.254) (xy -0.5334 0.254)
				(xy -0.5334 0.2794)
			)
			(stroke
				(width 0)
				(type default)
			)
			(fill no)
			(layer "B.CrtYd")
		)
		(pad "1" smd rect
			(at -0.40005 0 90)
			(size 0.4572 0.508)
			(layers "B.Cu" "B.Mask" "B.Paste")
			(net "UART_DTR_P4_N")
		)
		(pad "2" smd rect
			(at 0.40005 0 90)
			(size 0.4572 0.508)
			(layers "B.Cu" "B.Mask" "B.Paste")
			(net "GND")
		)
	)
	(footprint ""
		(layer "B.Cu")
		(at 69.143372 -80.514698 90)
		(property "Reference" "C67"
			(at -32.158686 -14.55039 270)
			(unlocked yes)
			(layer "B.SilkS")
			(effects
				(font
					(size 0.7874 0.5842)
					(thickness 0.1524)
				)
				(justify left mirror)
			)
		)
		(property "Value" ""
			(at 0 0 90)
			(layer "B.Fab")
			(effects
				(font
					(size 1.27 1.27)
				)
				(justify mirror)
			)
		)
		(duplicate_pad_numbers_are_jumpers no)
		(fp_line
			(start 0.7874 -0.4064)
			(end -0.7874 -0.4064)
			(stroke
				(width 0.1524)
				(type default)
			)
			(layer "B.SilkS")
		)
		(fp_line
			(start -0.7874 -0.4064)
			(end -0.7874 0.4064)
			(stroke
				(width 0.1524)
				(type default)
			)
			(layer "B.SilkS")
		)
		(fp_line
			(start 0 0.381)
			(end 0 -0.381)
			(stroke
				(width 0.1524)
				(type default)
			)
			(layer "B.SilkS")
		)
		(fp_line
			(start 0.7874 0.4064)
			(end 0.7874 -0.4064)
			(stroke
				(width 0.1524)
				(type default)
			)
			(layer "B.SilkS")
		)
		(fp_line
			(start -0.7874 0.4064)
			(end 0.7874 0.4064)
			(stroke
				(width 0.1524)
				(type default)
			)
			(layer "B.SilkS")
		)
		(fp_poly
			(pts
				(xy 0.5334 0.254) (xy 0.635 0.254) (xy 0.635 0.2286) (xy 0.635 -0.254) (xy 0.5334 -0.254) (xy 0.5334 -0.2794)
				(xy -0.5334 -0.2794) (xy -0.5334 -0.254) (xy -0.635 -0.254) (xy -0.635 0.254) (xy -0.5334 0.254)
				(xy -0.5334 0.2794) (xy 0.508 0.2794) (xy 0.5334 0.2794)
			)
			(stroke
				(width 0)
				(type default)
			)
			(fill no)
			(layer "B.CrtYd")
		)
		(pad "1" smd rect
			(at -0.40005 0 270)
			(size 0.4572 0.508)
			(layers "B.Cu" "B.Mask" "B.Paste")
			(net "PV_VCCP_NODE1")
		)
		(pad "2" smd rect
			(at 0.40005 0 270)
			(size 0.4572 0.508)
			(layers "B.Cu" "B.Mask" "B.Paste")
			(net "GND")
		)
	)
	(footprint ""
		(layer "B.Cu")
		(at 91.47302 -73.740518)
		(property "Reference" "R158"
			(at 4.07797 0.606044 0)
			(unlocked yes)
			(layer "B.SilkS")
			(effects
				(font
					(size 0.7874 0.5842)
					(thickness 0.1524)
				)
				(justify left mirror)
			)
		)
		(property "Value" ""
			(at 0 0 0)
			(layer "B.Fab")
			(effects
				(font
					(size 1.27 1.27)
				)
				(justify mirror)
			)
		)
		(duplicate_pad_numbers_are_jumpers no)
		(fp_line
			(start -0.7874 -0.4064)
			(end -0.7874 0.4064)
			(stroke
				(width 0.1524)
				(type default)
			)
			(layer "B.SilkS")
		)
		(fp_line
			(start -0.7874 0.4064)
			(end 0.7874 0.4064)
			(stroke
				(width 0.1524)
				(type default)
			)
			(layer "B.SilkS")
		)
		(fp_line
			(start 0.7874 -0.4064)
			(end -0.7874 -0.4064)
			(stroke
				(width 0.1524)
				(type default)
			)
			(layer "B.SilkS")
		)
		(fp_line
			(start 0.7874 0.4064)
			(end 0.7874 -0.4064)
			(stroke
				(width 0.1524)
				(type default)
			)
			(layer "B.SilkS")
		)
		(fp_poly
			(pts
				(xy 0.508 0.2794) (xy 0.508 0.2286) (xy 0.635 0.2286) (xy 0.635 -0.254) (xy 0.5334 -0.254) (xy 0.5334 -0.2794)
				(xy -0.5334 -0.2794) (xy -0.5334 -0.254) (xy -0.635 -0.254) (xy -0.635 0.254) (xy -0.5334 0.254)
				(xy -0.5334 0.2794)
			)
			(stroke
				(width 0)
				(type default)
			)
			(fill no)
			(layer "B.CrtYd")
		)
		(pad "1" smd rect
			(at -0.40005 0 180)
			(size 0.4572 0.508)
			(layers "B.Cu" "B.Mask" "B.Paste")
			(net "PD_CPU_NODE1_SPD_EN_L")
		)
		(pad "2" smd rect
			(at 0.40005 0 180)
			(size 0.4572 0.508)
			(layers "B.Cu" "B.Mask" "B.Paste")
			(net "P1V05_SUS_NODE1")
		)
	)
	(footprint ""
		(layer "B.Cu")
		(at 46.33722 -159.21609 -90)
		(property "Reference" "C421"
			(at -7.02437 7.212076 270)
			(unlocked yes)
			(layer "B.SilkS")
			(effects
				(font
					(size 0.7874 0.5842)
					(thickness 0.1524)
				)
				(justify left mirror)
			)
		)
		(property "Value" ""
			(at 0 0 90)
			(layer "B.Fab")
			(effects
				(font
					(size 1.27 1.27)
				)
				(justify mirror)
			)
		)
		(duplicate_pad_numbers_are_jumpers no)
		(fp_line
			(start -0.7874 0.4064)
			(end 0.7874 0.4064)
			(stroke
				(width 0.1524)
				(type default)
			)
			(layer "B.SilkS")
		)
		(fp_line
			(start 0.7874 0.4064)
			(end 0.7874 -0.4064)
			(stroke
				(width 0.1524)
				(type default)
			)
			(layer "B.SilkS")
		)
		(fp_line
			(start 0 0.381)
			(end 0 -0.381)
			(stroke
				(width 0.1524)
				(type default)
			)
			(layer "B.SilkS")
		)
		(fp_line
			(start -0.7874 -0.4064)
			(end -0.7874 0.4064)
			(stroke
				(width 0.1524)
				(type default)
			)
			(layer "B.SilkS")
		)
		(fp_line
			(start 0.7874 -0.4064)
			(end -0.7874 -0.4064)
			(stroke
				(width 0.1524)
				(type default)
			)
			(layer "B.SilkS")
		)
		(fp_poly
			(pts
				(xy 0.5334 0.254) (xy 0.635 0.254) (xy 0.635 0.2286) (xy 0.635 -0.254) (xy 0.5334 -0.254) (xy 0.5334 -0.2794)
				(xy -0.5334 -0.2794) (xy -0.5334 -0.254) (xy -0.635 -0.254) (xy -0.635 0.254) (xy -0.5334 0.254)
				(xy -0.5334 0.2794) (xy 0.508 0.2794) (xy 0.5334 0.2794)
			)
			(stroke
				(width 0)
				(type default)
			)
			(fill no)
			(layer "B.CrtYd")
		)
		(pad "1" smd rect
			(at -0.40005 0 90)
			(size 0.4572 0.508)
			(layers "B.Cu" "B.Mask" "B.Paste")
			(net "P1V05_LAN1")
		)
		(pad "2" smd rect
			(at 0.40005 0 90)
			(size 0.4572 0.508)
			(layers "B.Cu" "B.Mask" "B.Paste")
			(net "GND")
		)
	)
	(footprint ""
		(layer "B.Cu")
		(at 162.80638 -148.880322 90)
		(property "Reference" "C452"
			(at -8.513318 0.318262 270)
			(unlocked yes)
			(layer "B.SilkS")
			(effects
				(font
					(size 0.7874 0.5842)
					(thickness 0.1524)
				)
				(justify left mirror)
			)
		)
		(property "Value" ""
			(at 0 0 90)
			(layer "B.Fab")
			(effects
				(font
					(size 1.27 1.27)
				)
				(justify mirror)
			)
		)
		(duplicate_pad_numbers_are_jumpers no)
		(fp_line
			(start 0.7874 -0.4064)
			(end -0.7874 -0.4064)
			(stroke
				(width 0.1524)
				(type default)
			)
			(layer "B.SilkS")
		)
		(fp_line
			(start -0.7874 -0.4064)
			(end -0.7874 0.4064)
			(stroke
				(width 0.1524)
				(type default)
			)
			(layer "B.SilkS")
		)
		(fp_line
			(start 0 0.381)
			(end 0 -0.381)
			(stroke
				(width 0.1524)
				(type default)
			)
			(layer "B.SilkS")
		)
		(fp_line
			(start 0.7874 0.4064)
			(end 0.7874 -0.4064)
			(stroke
				(width 0.1524)
				(type default)
			)
			(layer "B.SilkS")
		)
		(fp_line
			(start -0.7874 0.4064)
			(end 0.7874 0.4064)
			(stroke
				(width 0.1524)
				(type default)
			)
			(layer "B.SilkS")
		)
		(fp_poly
			(pts
				(xy 0.5334 0.254) (xy 0.635 0.254) (xy 0.635 0.2286) (xy 0.635 -0.254) (xy 0.5334 -0.254) (xy 0.5334 -0.2794)
				(xy -0.5334 -0.2794) (xy -0.5334 -0.254) (xy -0.635 -0.254) (xy -0.635 0.254) (xy -0.5334 0.254)
				(xy -0.5334 0.2794) (xy 0.508 0.2794) (xy 0.5334 0.2794)
			)
			(stroke
				(width 0)
				(type default)
			)
			(fill no)
			(layer "B.CrtYd")
		)
		(pad "1" smd rect
			(at -0.40005 0 270)
			(size 0.4572 0.508)
			(layers "B.Cu" "B.Mask" "B.Paste")
			(net "P1V9_LAN2")
		)
		(pad "2" smd rect
			(at 0.40005 0 270)
			(size 0.4572 0.508)
			(layers "B.Cu" "B.Mask" "B.Paste")
			(net "GND")
		)
	)
	(footprint ""
		(layer "B.Cu")
		(at 40.39362 -156.65069)
		(property "Reference" "C411"
			(at -6.504178 -9.453372 0)
			(unlocked yes)
			(layer "B.SilkS")
			(effects
				(font
					(size 0.7874 0.5842)
					(thickness 0.1524)
				)
				(justify left mirror)
			)
		)
		(property "Value" ""
			(at 0 0 0)
			(layer "B.Fab")
			(effects
				(font
					(size 1.27 1.27)
				)
				(justify mirror)
			)
		)
		(duplicate_pad_numbers_are_jumpers no)
		(fp_line
			(start -0.7874 -0.4064)
			(end -0.7874 0.4064)
			(stroke
				(width 0.1524)
				(type default)
			)
			(layer "B.SilkS")
		)
		(fp_line
			(start -0.7874 0.4064)
			(end 0.7874 0.4064)
			(stroke
				(width 0.1524)
				(type default)
			)
			(layer "B.SilkS")
		)
		(fp_line
			(start 0 0.381)
			(end 0 -0.381)
			(stroke
				(width 0.1524)
				(type default)
			)
			(layer "B.SilkS")
		)
		(fp_line
			(start 0.7874 -0.4064)
			(end -0.7874 -0.4064)
			(stroke
				(width 0.1524)
				(type default)
			)
			(layer "B.SilkS")
		)
		(fp_line
			(start 0.7874 0.4064)
			(end 0.7874 -0.4064)
			(stroke
				(width 0.1524)
				(type default)
			)
			(layer "B.SilkS")
		)
		(fp_poly
			(pts
				(xy 0.5334 0.254) (xy 0.635 0.254) (xy 0.635 0.2286) (xy 0.635 -0.254) (xy 0.5334 -0.254) (xy 0.5334 -0.2794)
				(xy -0.5334 -0.2794) (xy -0.5334 -0.254) (xy -0.635 -0.254) (xy -0.635 0.254) (xy -0.5334 0.254)
				(xy -0.5334 0.2794) (xy 0.508 0.2794) (xy 0.5334 0.2794)
			)
			(stroke
				(width 0)
				(type default)
			)
			(fill no)
			(layer "B.CrtYd")
		)
		(pad "1" smd rect
			(at -0.40005 0 180)
			(size 0.4572 0.508)
			(layers "B.Cu" "B.Mask" "B.Paste")
			(net "P1V9_LAN1")
		)
		(pad "2" smd rect
			(at 0.40005 0 180)
			(size 0.4572 0.508)
			(layers "B.Cu" "B.Mask" "B.Paste")
			(net "GND")
		)
	)
	(footprint ""
		(layer "B.Cu")
		(at 59.997086 -146.419062 90)
		(property "Reference" "R291"
			(at 0.94742 -0.289306 270)
			(unlocked yes)
			(layer "B.SilkS")
			(effects
				(font
					(size 0.7874 0.5842)
					(thickness 0.1524)
				)
				(justify left mirror)
			)
		)
		(property "Value" ""
			(at 0 0 90)
			(layer "B.Fab")
			(effects
				(font
					(size 1.27 1.27)
				)
				(justify mirror)
			)
		)
		(duplicate_pad_numbers_are_jumpers no)
		(fp_line
			(start 0.7874 -0.4064)
			(end -0.7874 -0.4064)
			(stroke
				(width 0.1524)
				(type default)
			)
			(layer "B.SilkS")
		)
		(fp_line
			(start -0.7874 -0.4064)
			(end -0.7874 0.4064)
			(stroke
				(width 0.1524)
				(type default)
			)
			(layer "B.SilkS")
		)
		(fp_line
			(start 0.7874 0.4064)
			(end 0.7874 -0.4064)
			(stroke
				(width 0.1524)
				(type default)
			)
			(layer "B.SilkS")
		)
		(fp_line
			(start -0.7874 0.4064)
			(end 0.7874 0.4064)
			(stroke
				(width 0.1524)
				(type default)
			)
			(layer "B.SilkS")
		)
		(fp_poly
			(pts
				(xy 0.508 0.2794) (xy 0.508 0.2286) (xy 0.635 0.2286) (xy 0.635 -0.254) (xy 0.5334 -0.254) (xy 0.5334 -0.2794)
				(xy -0.5334 -0.2794) (xy -0.5334 -0.254) (xy -0.635 -0.254) (xy -0.635 0.254) (xy -0.5334 0.254)
				(xy -0.5334 0.2794)
			)
			(stroke
				(width 0)
				(type default)
			)
			(fill no)
			(layer "B.CrtYd")
		)
		(pad "1" smd rect
			(at -0.40005 0 270)
			(size 0.4572 0.508)
			(layers "B.Cu" "B.Mask" "B.Paste")
			(net "BMC_NODE1_GFX_GREEN")
		)
		(pad "2" smd rect
			(at 0.40005 0 270)
			(size 0.4572 0.508)
			(layers "B.Cu" "B.Mask" "B.Paste")
			(net "GND")
		)
	)
	(footprint ""
		(layer "B.Cu")
		(at 42.551858 -72.478138 180)
		(property "Reference" "R37"
			(at 0.923036 -1.577848 0)
			(unlocked yes)
			(layer "B.SilkS")
			(effects
				(font
					(size 0.7874 0.5842)
					(thickness 0.1524)
				)
				(justify left mirror)
			)
		)
		(property "Value" ""
			(at 0 0 0)
			(layer "B.Fab")
			(effects
				(font
					(size 1.27 1.27)
				)
				(justify mirror)
			)
		)
		(duplicate_pad_numbers_are_jumpers no)
		(fp_line
			(start 0.7874 0.4064)
			(end 0.7874 -0.4064)
			(stroke
				(width 0.1524)
				(type default)
			)
			(layer "B.SilkS")
		)
		(fp_line
			(start 0.7874 -0.4064)
			(end -0.7874 -0.4064)
			(stroke
				(width 0.1524)
				(type default)
			)
			(layer "B.SilkS")
		)
		(fp_line
			(start -0.7874 0.4064)
			(end 0.7874 0.4064)
			(stroke
				(width 0.1524)
				(type default)
			)
			(layer "B.SilkS")
		)
		(fp_line
			(start -0.7874 -0.4064)
			(end -0.7874 0.4064)
			(stroke
				(width 0.1524)
				(type default)
			)
			(layer "B.SilkS")
		)
		(fp_poly
			(pts
				(xy 0.508 0.2794) (xy 0.508 0.2286) (xy 0.635 0.2286) (xy 0.635 -0.254) (xy 0.5334 -0.254) (xy 0.5334 -0.2794)
				(xy -0.5334 -0.2794) (xy -0.5334 -0.254) (xy -0.635 -0.254) (xy -0.635 0.254) (xy -0.5334 0.254)
				(xy -0.5334 0.2794)
			)
			(stroke
				(width 0)
				(type default)
			)
			(fill no)
			(layer "B.CrtYd")
		)
		(pad "1" smd rect
			(at -0.40005 0)
			(size 0.4572 0.508)
			(layers "B.Cu" "B.Mask" "B.Paste")
			(net "PD_CPU_NODE1_AN5")
		)
		(pad "2" smd rect
			(at 0.40005 0)
			(size 0.4572 0.508)
			(layers "B.Cu" "B.Mask" "B.Paste")
			(net "GND")
		)
	)
)
